(kicad_pcb
	(version 20260206)
	(generator "pcbnew")
	(generator_version "10.0")
	(general
		(thickness 1.6)
		(legacy_teardrops no)
	)
	(paper "A4")
	(title_block
		(title "panther-plus-userver — 13130-1b_20150205.brd")
		(comment 1 "Honey Badger (Wiwynn) / footprints 2-8 of 1509")
	)
	(layers
		(0 "F.Cu" signal "TOP")
		(4 "In1.Cu" signal "L2")
		(6 "In2.Cu" signal "L3")
		(8 "In3.Cu" signal "L4")
		(10 "In4.Cu" signal "L5")
		(12 "In5.Cu" signal "L6")
		(14 "In6.Cu" signal "L7")
		(16 "In7.Cu" signal "L8")
		(18 "In8.Cu" signal "L9")
		(20 "In9.Cu" signal "L10")
		(22 "In10.Cu" signal "L11")
		(2 "B.Cu" signal "BOTTOM")
		(9 "F.Adhes" user "F.Adhesive")
		(11 "B.Adhes" user "B.Adhesive")
		(13 "F.Paste" user "Package Geometry/Pastemask Top")
		(15 "B.Paste" user "Package Geometry/Pastemask Bottom")
		(5 "F.SilkS" user "Ref Des/Silkscreen Top")
		(7 "B.SilkS" user "Ref Des/Silkscreen Bottom")
		(1 "F.Mask" user "Board Geometry/Soldermask Top")
		(3 "B.Mask" user "Board Geometry/Soldermask Bottom")
		(17 "Dwgs.User" user "User.Drawings")
		(19 "Cmts.User" user "User.Comments")
		(21 "Eco1.User" user "User.Eco1")
		(23 "Eco2.User" user "User.Eco2")
		(25 "Edge.Cuts" user "Board Geometry/Outline")
		(27 "Margin" user)
		(31 "F.CrtYd" user "Package Geometry/Place Bound Top")
		(29 "B.CrtYd" user "Package Geometry/Place Bound Bottom")
		(35 "F.Fab" user "Ref Des/Assembly Top")
		(33 "B.Fab" user "Ref Des/Assembly Bottom")
	)
	(footprint ""
		(layer "F.Cu")
		(at 19.304 -33.147 180)
		(property "Reference" "PC172"
			(at 0 0 180)
			(layer "F.SilkS")
			(hide yes)
			(effects
				(font
					(size 1.27 1.27)
				)
			)
		)
		(property "Value" "SC1U10V2KX-1GP"
			(at 1.8923 -1.2065 180)
			(unlocked yes)
			(layer "F.Fab")
			(hide yes)
			(effects
				(font
					(size 1.016 1.016)
					(thickness 0.1524)
				)
			)
		)
		(property "Device Type" "C402H22"
			(at 1.8923 -2.7305 180)
			(unlocked yes)
			(layer "F.Fab")
			(hide yes)
			(effects
				(font
					(size 1.016 1.016)
					(thickness 0.1524)
				)
			)
		)
		(duplicate_pad_numbers_are_jumpers no)
		(fp_rect
			(start -0.381 0.7366)
			(end 0.381 -0.7366)
			(stroke
				(width 0)
				(type default)
			)
			(fill no)
			(layer "F.CrtYd")
		)
		(fp_rect
			(start -0.381 0.7366)
			(end 0.381 -0.7366)
			(stroke
				(width 0)
				(type default)
			)
			(fill no)
			(layer "F.Fab")
		)
		(pad "1" smd custom
			(at 0 -0.4572 180)
			(size 0.1143 0.1143)
			(layers "F.Cu" "F.Mask" "F.Paste")
			(net "P3V3_STBY_VFB")
			(options
				(clearance outline)
				(anchor circle)
			)
			(primitives
				(gr_poly
					(pts
						(arc
							(start -0.254 -0.1778)
							(mid -0.239121 -0.213721)
							(end -0.2032 -0.2286)
						)
						(arc
							(start 0.2032 -0.2286)
							(mid 0.239121 -0.213721)
							(end 0.254 -0.1778)
						)
						(arc
							(start 0.254 0.1778)
							(mid 0.239121 0.213721)
							(end 0.2032 0.2286)
						)
						(arc
							(start -0.2032 0.2286)
							(mid -0.239121 0.213721)
							(end -0.254 0.1778)
						)
					)
					(width 0)
					(fill yes)
				)
			)
		)
		(pad "2" smd custom
			(at 0 0.4572 180)
			(size 0.1143 0.1143)
			(layers "F.Cu" "F.Mask" "F.Paste")
			(net "P3V3_STBY_VFB_R")
			(options
				(clearance outline)
				(anchor circle)
			)
			(primitives
				(gr_poly
					(pts
						(arc
							(start -0.254 -0.1778)
							(mid -0.239121 -0.213721)
							(end -0.2032 -0.2286)
						)
						(arc
							(start 0.2032 -0.2286)
							(mid 0.239121 -0.213721)
							(end 0.254 -0.1778)
						)
						(arc
							(start 0.254 0.1778)
							(mid 0.239121 0.213721)
							(end 0.2032 0.2286)
						)
						(arc
							(start -0.2032 0.2286)
							(mid -0.239121 0.213721)
							(end -0.254 0.1778)
						)
					)
					(width 0)
					(fill yes)
				)
			)
		)
	)
	(footprint ""
		(layer "F.Cu")
		(at 54.4322 -15.3416 180)
		(property "Reference" "Q18"
			(at 0 0 180)
			(layer "F.SilkS")
			(hide yes)
			(effects
				(font
					(size 1.27 1.27)
				)
			)
		)
		(property "Value" "2N7002A-7-GP"
			(at -4.3561 -5.7912 180)
			(unlocked yes)
			(layer "F.Fab")
			(hide yes)
			(effects
				(font
					(size 1.016 1.016)
					(thickness 0.1524)
				)
			)
		)
		(property "Device Type" "SOT23DGS2D4H48"
			(at -4.3561 -7.3152 180)
			(unlocked yes)
			(layer "F.Fab")
			(hide yes)
			(effects
				(font
					(size 1.016 1.016)
					(thickness 0.1524)
				)
			)
		)
		(duplicate_pad_numbers_are_jumpers no)
		(fp_line
			(start 1.7145 0.4445)
			(end 1.7145 -0.4445)
			(stroke
				(width 0.1524)
				(type default)
			)
			(layer "F.SilkS")
		)
		(fp_line
			(start 1.7145 -0.4445)
			(end -1.7145 -0.4445)
			(stroke
				(width 0.1524)
				(type default)
			)
			(layer "F.SilkS")
		)
		(fp_line
			(start -1.7145 0.4445)
			(end 1.7145 0.4445)
			(stroke
				(width 0.1524)
				(type default)
			)
			(layer "F.SilkS")
		)
		(fp_line
			(start -1.7145 -0.4445)
			(end -1.7145 0.4445)
			(stroke
				(width 0.1524)
				(type default)
			)
			(layer "F.SilkS")
		)
		(fp_poly
			(pts
				(xy -1.4224 1.5621) (xy -1.4224 0.9017) (xy -1.7145 0.9017) (xy -1.7145 -0.9017) (xy -0.4699 -0.9017)
				(xy -0.4699 -1.5621) (xy 0.4699 -1.5621) (xy 0.4699 -0.9017) (xy 1.7145 -0.9017) (xy 1.7145 0.9017)
				(xy 1.4224 0.9017) (xy 1.4224 1.5621) (xy 0.4826 1.5621) (xy 0.4826 0.9017) (xy -0.4826 0.9017)
				(xy -0.4826 1.5621)
			)
			(stroke
				(width 0)
				(type default)
			)
			(fill no)
			(layer "F.CrtYd")
		)
		(fp_poly
			(pts
				(xy -1.4224 1.5621) (xy -1.4224 0.9017) (xy -1.7145 0.9017) (xy -1.7145 -0.9017) (xy -0.4699 -0.9017)
				(xy -0.4699 -1.5621) (xy 0.4699 -1.5621) (xy 0.4699 -0.9017) (xy 1.7145 -0.9017) (xy 1.7145 0.9017)
				(xy 1.4224 0.9017) (xy 1.4224 1.5621) (xy 0.4826 1.5621) (xy 0.4826 0.9017) (xy -0.4826 0.9017)
				(xy -0.4826 1.5621)
			)
			(stroke
				(width 0)
				(type default)
			)
			(fill no)
			(layer "F.Fab")
		)
		(pad "D" smd custom
			(at 0 -1.069086 180)
			(size 0.17145 0.17145)
			(layers "F.Cu" "F.Mask" "F.Paste")
			(net "GF_GBE_SMBALRT#")
			(options
				(clearance outline)
				(anchor circle)
			)
			(primitives
				(gr_poly
					(pts
						(arc
							(start -0.1397 0.3683)
							(mid -0.283384 0.308784)
							(end -0.3429 0.1651)
						)
						(arc
							(start -0.3429 -0.1651)
							(mid -0.283384 -0.308784)
							(end -0.1397 -0.3683)
						)
						(arc
							(start 0.1397 -0.3683)
							(mid 0.283384 -0.308784)
							(end 0.3429 -0.1651)
						)
						(arc
							(start 0.3429 0.1651)
							(mid 0.283384 0.308784)
							(end 0.1397 0.3683)
						)
					)
					(width 0)
					(fill yes)
				)
			)
		)
		(pad "G" smd custom
			(at -0.94996 1.069086 180)
			(size 0.17145 0.17145)
			(layers "F.Cu" "F.Mask" "F.Paste")
			(net "GF_GBE_SMB_SW_EN")
			(options
				(clearance outline)
				(anchor circle)
			)
			(primitives
				(gr_poly
					(pts
						(arc
							(start -0.1397 0.3683)
							(mid -0.283384 0.308784)
							(end -0.3429 0.1651)
						)
						(arc
							(start -0.3429 -0.1651)
							(mid -0.283384 -0.308784)
							(end -0.1397 -0.3683)
						)
						(arc
							(start 0.1397 -0.3683)
							(mid 0.283384 -0.308784)
							(end 0.3429 -0.1651)
						)
						(arc
							(start 0.3429 0.1651)
							(mid 0.283384 0.308784)
							(end 0.1397 0.3683)
						)
					)
					(width 0)
					(fill yes)
				)
			)
		)
		(pad "S" smd custom
			(at 0.94996 1.069086 180)
			(size 0.17145 0.17145)
			(layers "F.Cu" "F.Mask" "F.Paste")
			(net "GBE_SMBALRT#")
			(options
				(clearance outline)
				(anchor circle)
			)
			(primitives
				(gr_poly
					(pts
						(arc
							(start -0.1397 0.3683)
							(mid -0.283384 0.308784)
							(end -0.3429 0.1651)
						)
						(arc
							(start -0.3429 -0.1651)
							(mid -0.283384 -0.308784)
							(end -0.1397 -0.3683)
						)
						(arc
							(start 0.1397 -0.3683)
							(mid 0.283384 -0.308784)
							(end 0.3429 -0.1651)
						)
						(arc
							(start 0.3429 0.1651)
							(mid 0.283384 0.308784)
							(end 0.1397 0.3683)
						)
					)
					(width 0)
					(fill yes)
				)
			)
		)
	)
	(footprint ""
		(layer "F.Cu")
		(at 167.894 -35.433 90)
		(property "Reference" "PR107"
			(at 0 0 90)
			(layer "F.SilkS")
			(hide yes)
			(effects
				(font
					(size 1.27 1.27)
				)
			)
		)
		(property "Value" "0R3J-6-GP"
			(at -0.0254 -2.5146 90)
			(unlocked yes)
			(layer "F.Fab")
			(hide yes)
			(effects
				(font
					(size 1.016 1.016)
					(thickness 0.1524)
				)
			)
		)
		(property "Device Type" "R603H22"
			(at -0.0254 -4.0386 90)
			(unlocked yes)
			(layer "F.Fab")
			(hide yes)
			(effects
				(font
					(size 1.016 1.016)
					(thickness 0.1524)
				)
			)
		)
		(duplicate_pad_numbers_are_jumpers no)
		(fp_line
			(start 0.4318 0)
			(end 0.2032 0)
			(stroke
				(width 0.2032)
				(type default)
			)
			(layer "F.SilkS")
		)
		(fp_line
			(start -0.2032 0)
			(end -0.4191 0)
			(stroke
				(width 0.2032)
				(type default)
			)
			(layer "F.SilkS")
		)
		(fp_rect
			(start -0.635 1.1811)
			(end 0.635 -1.1811)
			(stroke
				(width 0)
				(type default)
			)
			(fill no)
			(layer "F.CrtYd")
		)
		(fp_rect
			(start -0.635 1.1811)
			(end 0.635 -1.1811)
			(stroke
				(width 0)
				(type default)
			)
			(fill no)
			(layer "F.Fab")
		)
		(pad "1" smd custom
			(at 0 -0.6604 90)
			(size 0.19685 0.19685)
			(layers "F.Cu" "F.Mask" "F.Paste")
			(net "P1V2_FPGA_A")
			(options
				(clearance outline)
				(anchor circle)
			)
			(primitives
				(gr_poly
					(pts
						(arc
							(start 0.508 -0.2921)
							(mid 0.478242 -0.363942)
							(end 0.4064 -0.3937)
						)
						(arc
							(start -0.4064 -0.3937)
							(mid -0.478242 -0.363942)
							(end -0.508 -0.2921)
						)
						(arc
							(start -0.508 0.2921)
							(mid -0.478242 0.363942)
							(end -0.4064 0.3937)
						)
						(arc
							(start 0.4064 0.3937)
							(mid 0.478242 0.363942)
							(end 0.508 0.2921)
						)
					)
					(width 0)
					(fill yes)
				)
			)
		)
		(pad "2" smd custom
			(at 0 0.6604 90)
			(size 0.19685 0.19685)
			(layers "F.Cu" "F.Mask" "F.Paste")
			(net "P1V2_STBY_LDO_OUT1")
			(options
				(clearance outline)
				(anchor circle)
			)
			(primitives
				(gr_poly
					(pts
						(arc
							(start 0.508 -0.2921)
							(mid 0.478242 -0.363942)
							(end 0.4064 -0.3937)
						)
						(arc
							(start -0.4064 -0.3937)
							(mid -0.478242 -0.363942)
							(end -0.508 -0.2921)
						)
						(arc
							(start -0.508 0.2921)
							(mid -0.478242 0.363942)
							(end -0.4064 0.3937)
						)
						(arc
							(start 0.4064 0.3937)
							(mid 0.478242 0.363942)
							(end 0.508 0.2921)
						)
					)
					(width 0)
					(fill yes)
				)
			)
		)
	)
	(footprint ""
		(layer "F.Cu")
		(at 188.595 -16.129 180)
		(property "Reference" "PR170"
			(at 0 0 180)
			(layer "F.SilkS")
			(hide yes)
			(effects
				(font
					(size 1.27 1.27)
				)
			)
		)
		(property "Value" "0R3J-0-U-GP"
			(at -0.0254 -2.5146 180)
			(unlocked yes)
			(layer "F.Fab")
			(hide yes)
			(effects
				(font
					(size 1.016 1.016)
					(thickness 0.1524)
				)
			)
		)
		(property "Device Type" "R603H22"
			(at -0.0254 -4.0386 180)
			(unlocked yes)
			(layer "F.Fab")
			(hide yes)
			(effects
				(font
					(size 1.016 1.016)
					(thickness 0.1524)
				)
			)
		)
		(duplicate_pad_numbers_are_jumpers no)
		(fp_line
			(start 0.4318 0)
			(end 0.2032 0)
			(stroke
				(width 0.2032)
				(type default)
			)
			(layer "F.SilkS")
		)
		(fp_line
			(start -0.2032 0)
			(end -0.4191 0)
			(stroke
				(width 0.2032)
				(type default)
			)
			(layer "F.SilkS")
		)
		(fp_rect
			(start -0.635 1.1811)
			(end 0.635 -1.1811)
			(stroke
				(width 0)
				(type default)
			)
			(fill no)
			(layer "F.CrtYd")
		)
		(fp_rect
			(start -0.635 1.1811)
			(end 0.635 -1.1811)
			(stroke
				(width 0)
				(type default)
			)
			(fill no)
			(layer "F.Fab")
		)
		(pad "1" smd custom
			(at 0 -0.6604 180)
			(size 0.19685 0.19685)
			(layers "F.Cu" "F.Mask" "F.Paste")
			(net "PV_VTT_DDR_B")
			(options
				(clearance outline)
				(anchor circle)
			)
			(primitives
				(gr_poly
					(pts
						(arc
							(start 0.508 -0.2921)
							(mid 0.478242 -0.363942)
							(end 0.4064 -0.3937)
						)
						(arc
							(start -0.4064 -0.3937)
							(mid -0.478242 -0.363942)
							(end -0.508 -0.2921)
						)
						(arc
							(start -0.508 0.2921)
							(mid -0.478242 0.363942)
							(end -0.4064 0.3937)
						)
						(arc
							(start 0.4064 0.3937)
							(mid 0.478242 0.363942)
							(end 0.508 0.2921)
						)
					)
					(width 0)
					(fill yes)
				)
			)
		)
		(pad "2" smd custom
			(at 0 0.6604 180)
			(size 0.19685 0.19685)
			(layers "F.Cu" "F.Mask" "F.Paste")
			(net "PV_VTT_DDR_B_SNS")
			(options
				(clearance outline)
				(anchor circle)
			)
			(primitives
				(gr_poly
					(pts
						(arc
							(start 0.508 -0.2921)
							(mid 0.478242 -0.363942)
							(end 0.4064 -0.3937)
						)
						(arc
							(start -0.4064 -0.3937)
							(mid -0.478242 -0.363942)
							(end -0.508 -0.2921)
						)
						(arc
							(start -0.508 0.2921)
							(mid -0.478242 0.363942)
							(end -0.4064 0.3937)
						)
						(arc
							(start 0.4064 0.3937)
							(mid 0.478242 0.363942)
							(end 0.508 0.2921)
						)
					)
					(width 0)
					(fill yes)
				)
			)
		)
	)
	(footprint ""
		(layer "F.Cu")
		(at 61.214 -56.769)
		(property "Reference" "PC60"
			(at 0 0 0)
			(layer "F.SilkS")
			(hide yes)
			(effects
				(font
					(size 1.27 1.27)
				)
			)
		)
		(property "Value" "SC47U6D3V5MX-1-GP"
			(at -0.0762 -6.1214 0)
			(unlocked yes)
			(layer "F.Fab")
			(hide yes)
			(effects
				(font
					(size 1.016 1.016)
					(thickness 0.1524)
				)
			)
		)
		(property "Device Type" "C805H54"
			(at -0.0762 -8.1534 0)
			(unlocked yes)
			(layer "F.Fab")
			(hide yes)
			(effects
				(font
					(size 1.016 1.016)
					(thickness 0.1524)
				)
			)
		)
		(duplicate_pad_numbers_are_jumpers no)
		(fp_line
			(start 0.6096 0)
			(end -0.6096 0)
			(stroke
				(width 0.3048)
				(type default)
			)
			(layer "F.SilkS")
		)
		(fp_poly
			(pts
				(xy -0.9017 1.4351) (xy 0.9017 1.4351) (xy 0.9017 -1.4351) (xy -0.9017 -1.4351)
			)
			(stroke
				(width 0)
				(type default)
			)
			(fill no)
			(layer "F.CrtYd")
		)
		(fp_poly
			(pts
				(xy 0.9017 1.4351) (xy 0.9017 -1.4351) (xy -0.9017 -1.4351) (xy -0.9017 1.4351)
			)
			(stroke
				(width 0)
				(type default)
			)
			(fill no)
			(layer "F.Fab")
		)
		(pad "1" smd rect
			(at 0 -0.8382)
			(size 1.5494 0.9398)
			(layers "F.Cu" "F.Mask" "F.Paste")
			(net "PVCCP")
		)
		(pad "2" smd rect
			(at 0 0.8382)
			(size 1.5494 0.9398)
			(layers "F.Cu" "F.Mask" "F.Paste")
			(net "GND")
		)
	)
	(footprint ""
		(layer "F.Cu")
		(at 44.45 -42.545 90)
		(property "Reference" "U10"
			(at 0 0 90)
			(layer "F.SilkS")
			(hide yes)
			(effects
				(font
					(size 1.27 1.27)
				)
			)
		)
		(property "Value" "SN74LVC1G14DCKR-GP"
			(at 0 -8.0772 90)
			(unlocked yes)
			(layer "F.Fab")
			(hide yes)
			(effects
				(font
					(size 1.016 1.016)
					(thickness 0.1524)
				)
			)
		)
		(property "Device Type" "SC70-5H44"
			(at 0 -9.6012 90)
			(unlocked yes)
			(layer "F.Fab")
			(hide yes)
			(effects
				(font
					(size 1.016 1.016)
					(thickness 0.1524)
				)
			)
		)
		(duplicate_pad_numbers_are_jumpers no)
		(fp_line
			(start 1.0033 -0.3302)
			(end 1.0033 0.3302)
			(stroke
				(width 0.1524)
				(type default)
			)
			(layer "F.SilkS")
		)
		(fp_line
			(start -1.0033 -0.3302)
			(end 1.0033 -0.3302)
			(stroke
				(width 0.1524)
				(type default)
			)
			(layer "F.SilkS")
		)
		(fp_line
			(start 1.0033 0.3302)
			(end -1.0033 0.3302)
			(stroke
				(width 0.1524)
				(type default)
			)
			(layer "F.SilkS")
		)
		(fp_line
			(start -1.0033 0.3302)
			(end -1.0033 -0.3302)
			(stroke
				(width 0.1524)
				(type default)
			)
			(layer "F.SilkS")
		)
		(fp_poly
			(pts
				(xy -1.0033 1.4859) (xy -1.0033 0.8001) (xy -1.1811 0.8001) (xy -1.1811 -0.8001) (xy -1.0033 -0.8001)
				(xy -1.0033 -1.4859) (xy 1.0033 -1.4859) (xy 1.0033 -0.8001) (xy 1.1811 -0.8001) (xy 1.1811 0.8001)
				(xy 1.0033 0.8001) (xy 1.0033 1.4859) (xy 0.2921 1.4859) (xy 0.2921 0.8001) (xy -0.2921 0.8001)
				(xy -0.2921 1.4859)
			)
			(stroke
				(width 0)
				(type default)
			)
			(fill no)
			(layer "F.CrtYd")
		)
		(fp_poly
			(pts
				(xy -1.0033 1.4859) (xy -1.0033 0.8001) (xy -1.1811 0.8001) (xy -1.1811 -0.8001) (xy -1.0033 -0.8001)
				(xy -1.0033 -1.4859) (xy 1.0033 -1.4859) (xy 1.0033 -0.8001) (xy 1.1811 -0.8001) (xy 1.1811 0.8001)
				(xy 1.0033 0.8001) (xy 1.0033 1.4859) (xy 0.2921 1.4859) (xy 0.2921 0.8001) (xy -0.2921 0.8001)
				(xy -0.2921 1.4859)
			)
			(stroke
				(width 0)
				(type default)
			)
			(fill no)
			(layer "F.Fab")
		)
		(pad "1" smd rect
			(at 0.65024 -0.93472 90)
			(size 0.3556 0.762)
			(layers "F.Cu" "F.Mask" "F.Paste")
			(net "Net_405")
		)
		(pad "2" smd rect
			(at 0 -0.93472 90)
			(size 0.3556 0.762)
			(layers "F.Cu" "F.Mask" "F.Paste")
			(net "CLK_GEN_DELAY1_PG")
		)
		(pad "3" smd rect
			(at -0.65024 -0.93472 90)
			(size 0.3556 0.762)
			(layers "F.Cu" "F.Mask" "F.Paste")
			(net "GND")
		)
		(pad "4" smd rect
			(at -0.65024 0.93472 90)
			(size 0.3556 0.762)
			(layers "F.Cu" "F.Mask" "F.Paste")
			(net "CLK_GEN_DELAY2_PG")
		)
		(pad "5" smd rect
			(at 0.65024 0.93472 90)
			(size 0.3556 0.762)
			(layers "F.Cu" "F.Mask" "F.Paste")
			(net "P3V3")
		)
	)
	(footprint ""
		(layer "F.Cu")
		(at 47.879 -68.072 180)
		(property "Reference" "PC30"
			(at 0 0 180)
			(layer "F.SilkS")
			(hide yes)
			(effects
				(font
					(size 1.27 1.27)
				)
			)
		)
		(property "Value" "SC47U6D3V5MX-1-GP"
			(at 0 -4.9022 180)
			(unlocked yes)
			(layer "F.Fab")
			(hide yes)
			(effects
				(font
					(size 1.016 1.016)
					(thickness 0.1524)
				)
			)
		)
		(property "Device Type" "C805H54"
			(at 0 -6.8072 180)
			(unlocked yes)
			(layer "F.Fab")
			(hide yes)
			(effects
				(font
					(size 1.016 1.016)
					(thickness 0.1524)
				)
			)
		)
		(duplicate_pad_numbers_are_jumpers no)
		(fp_line
			(start 0.6096 0)
			(end -0.6096 0)
			(stroke
				(width 0.3048)
				(type default)
			)
			(layer "F.SilkS")
		)
		(fp_poly
			(pts
				(xy -0.9017 1.4351) (xy 0.9017 1.4351) (xy 0.9017 -1.4351) (xy -0.9017 -1.4351)
			)
			(stroke
				(width 0)
				(type default)
			)
			(fill no)
			(layer "F.CrtYd")
		)
		(fp_poly
			(pts
				(xy 0.9017 1.4351) (xy 0.9017 -1.4351) (xy -0.9017 -1.4351) (xy -0.9017 1.4351)
			)
			(stroke
				(width 0)
				(type default)
			)
			(fill no)
			(layer "F.Fab")
		)
		(pad "1" smd rect
			(at 0 -0.8382 180)
			(size 1.5494 0.9398)
			(layers "F.Cu" "F.Mask" "F.Paste")
			(net "PVNN")
		)
		(pad "2" smd rect
			(at 0 0.8382 180)
			(size 1.5494 0.9398)
			(layers "F.Cu" "F.Mask" "F.Paste")
			(net "GND")
		)
	)
)
